(kicad_pcb
	(version 20260206)
	(generator "pcbnew")
	(generator_version "10.0")
	(general
		(thickness 1.6)
		(legacy_teardrops no)
	)
	(paper "A4")
	(title_block
		(title "04192023_DAF0TMB3IC0_F0TG_MB_C_brd_V02_OCP.brd")
		(comment 1 "Grand Teton / footprints 7853-7858 of 8354")
	)
	(layers
		(0 "F.Cu" signal "TOP")
		(4 "In1.Cu" signal "GND")
		(6 "In2.Cu" signal "IN1")
		(8 "In3.Cu" signal "GND1")
		(10 "In4.Cu" signal "IN2")
		(12 "In5.Cu" signal "GND2")
		(14 "In6.Cu" signal "IN3")
		(16 "In7.Cu" signal "GND3")
		(18 "In8.Cu" signal "VCC")
		(20 "In9.Cu" signal "VCC1")
		(22 "In10.Cu" signal "GND4")
		(24 "In11.Cu" signal "IN4")
		(26 "In12.Cu" signal "GND5")
		(28 "In13.Cu" signal "IN5")
		(30 "In14.Cu" signal "GND6")
		(32 "In15.Cu" signal "IN6")
		(34 "In16.Cu" signal "GND7")
		(2 "B.Cu" signal "BOTTOM")
		(9 "F.Adhes" user "F.Adhesive")
		(11 "B.Adhes" user "B.Adhesive")
		(13 "F.Paste" user "Package Geometry/Pastemask Top")
		(15 "B.Paste" user "Package Geometry/Pastemask Bottom")
		(5 "F.SilkS" user "Ref Des/Silkscreen Top")
		(7 "B.SilkS" user "Ref Des/Silkscreen Bottom")
		(1 "F.Mask" user "Board Geometry/Soldermask Top")
		(3 "B.Mask" user "Board Geometry/Soldermask Bottom")
		(17 "Dwgs.User" user "User.Drawings")
		(19 "Cmts.User" user "User.Comments")
		(21 "Eco1.User" user "User.Eco1")
		(23 "Eco2.User" user "User.Eco2")
		(25 "Edge.Cuts" user "Board Geometry/Outline")
		(27 "Margin" user)
		(31 "F.CrtYd" user "Package Geometry/Place Bound Top")
		(29 "B.CrtYd" user "Package Geometry/Place Bound Bottom")
		(35 "F.Fab" user "Ref Des/Assembly Top")
		(33 "B.Fab" user "Ref Des/Assembly Bottom")
	)
	(footprint ""
		(layer "B.Cu")
		(at 448.051682 -53.20411 -90)
		(property "Reference" "PC8013"
			(at 0 0 90)
			(layer "B.SilkS")
			(hide yes)
			(effects
				(font
					(size 1.27 1.27)
				)
				(justify mirror)
			)
		)
		(property "Value" ""
			(at 0 0 90)
			(layer "B.Fab")
			(effects
				(font
					(size 1.27 1.27)
				)
				(justify mirror)
			)
		)
		(duplicate_pad_numbers_are_jumpers no)
		(fp_line
			(start -1.524 0.762)
			(end 1.524 0.762)
			(stroke
				(width 0.1524)
				(type default)
			)
			(layer "B.SilkS")
		)
		(fp_line
			(start 1.524 0.762)
			(end 1.524 -0.762)
			(stroke
				(width 0.1524)
				(type default)
			)
			(layer "B.SilkS")
		)
		(fp_line
			(start -1.524 -0.762)
			(end -1.524 0.762)
			(stroke
				(width 0.1524)
				(type default)
			)
			(layer "B.SilkS")
		)
		(fp_line
			(start 1.524 -0.762)
			(end -1.524 -0.762)
			(stroke
				(width 0.1524)
				(type default)
			)
			(layer "B.SilkS")
		)
		(fp_line
			(start -1.1049 0.724916)
			(end -1.1049 -0.724916)
			(stroke
				(width 0.1)
				(type default)
			)
			(layer "B.Fab")
		)
		(fp_line
			(start 1.1049 0.724916)
			(end -1.1049 0.724916)
			(stroke
				(width 0.1)
				(type default)
			)
			(layer "B.Fab")
		)
		(fp_line
			(start -1.1049 -0.724916)
			(end 1.1049 -0.724916)
			(stroke
				(width 0.1)
				(type default)
			)
			(layer "B.Fab")
		)
		(fp_line
			(start 1.1049 -0.724916)
			(end 1.1049 0.724916)
			(stroke
				(width 0.1)
				(type default)
			)
			(layer "B.Fab")
		)
		(pad "1" smd rect
			(at 0.889 0 270)
			(size 1.016 1.27)
			(layers "B.Cu" "B.Mask" "B.Paste")
			(net "SW_P3V3_AUX_FLT")
		)
		(pad "2" smd rect
			(at -0.889 0 270)
			(size 1.016 1.27)
			(layers "B.Cu" "B.Mask" "B.Paste")
			(net "GND")
		)
	)
	(footprint ""
		(layer "B.Cu")
		(at 47.391066 -390.560052 90)
		(property "Reference" "C250"
			(at 0 0 90)
			(layer "B.SilkS")
			(hide yes)
			(effects
				(font
					(size 1.27 1.27)
				)
				(justify mirror)
			)
		)
		(property "Value" ""
			(at 0 0 90)
			(layer "B.Fab")
			(effects
				(font
					(size 1.27 1.27)
				)
				(justify mirror)
			)
		)
		(duplicate_pad_numbers_are_jumpers no)
		(fp_line
			(start 0.7874 -0.4064)
			(end -0.7874 -0.4064)
			(stroke
				(width 0.1524)
				(type default)
			)
			(layer "B.SilkS")
		)
		(fp_line
			(start -0.7874 -0.4064)
			(end -0.7874 0.4064)
			(stroke
				(width 0.1524)
				(type default)
			)
			(layer "B.SilkS")
		)
		(fp_line
			(start 0.7874 0.4064)
			(end 0.7874 -0.4064)
			(stroke
				(width 0.1524)
				(type default)
			)
			(layer "B.SilkS")
		)
		(fp_line
			(start -0.7874 0.4064)
			(end 0.7874 0.4064)
			(stroke
				(width 0.1524)
				(type default)
			)
			(layer "B.SilkS")
		)
		(fp_line
			(start 0.67945 -0.305054)
			(end 0.12065 -0.305054)
			(stroke
				(width 0.1)
				(type default)
			)
			(layer "B.Fab")
		)
		(fp_line
			(start 0.12065 -0.305054)
			(end 0.12065 -0.2794)
			(stroke
				(width 0.1)
				(type default)
			)
			(layer "B.Fab")
		)
		(fp_line
			(start -0.12065 -0.3048)
			(end -0.67945 -0.3048)
			(stroke
				(width 0.1)
				(type default)
			)
			(layer "B.Fab")
		)
		(fp_line
			(start -0.67945 -0.3048)
			(end -0.67945 0.3048)
			(stroke
				(width 0.1)
				(type default)
			)
			(layer "B.Fab")
		)
		(fp_line
			(start 0.12065 -0.2794)
			(end -0.12065 -0.2794)
			(stroke
				(width 0.1)
				(type default)
			)
			(layer "B.Fab")
		)
		(fp_line
			(start -0.12065 -0.2794)
			(end -0.12065 -0.3048)
			(stroke
				(width 0.1)
				(type default)
			)
			(layer "B.Fab")
		)
		(fp_line
			(start 0.12065 0.2794)
			(end 0.12065 0.3048)
			(stroke
				(width 0.1)
				(type default)
			)
			(layer "B.Fab")
		)
		(fp_line
			(start -0.120396 0.2794)
			(end 0.12065 0.2794)
			(stroke
				(width 0.1)
				(type default)
			)
			(layer "B.Fab")
		)
		(fp_line
			(start 0.67945 0.3048)
			(end 0.67945 -0.305054)
			(stroke
				(width 0.1)
				(type default)
			)
			(layer "B.Fab")
		)
		(fp_line
			(start 0.12065 0.3048)
			(end 0.67945 0.3048)
			(stroke
				(width 0.1)
				(type default)
			)
			(layer "B.Fab")
		)
		(fp_line
			(start -0.120396 0.3048)
			(end -0.120396 0.2794)
			(stroke
				(width 0.1)
				(type default)
			)
			(layer "B.Fab")
		)
		(fp_line
			(start -0.67945 0.3048)
			(end -0.120396 0.3048)
			(stroke
				(width 0.1)
				(type default)
			)
			(layer "B.Fab")
		)
		(pad "1" smd circle
			(at 0.40005 0 270)
			(size 0 0)
			(layers "B.Cu" "B.Mask" "B.Paste")
			(net "P0V9_CPU1_RT0_2A")
		)
		(pad "2" smd circle
			(at -0.40005 0 270)
			(size 0 0)
			(layers "B.Cu" "B.Mask" "B.Paste")
			(net "GND")
		)
	)
	(footprint ""
		(layer "B.Cu")
		(at 271.760696 -349.381572 -90)
		(property "Reference" "PR112"
			(at 0 0 90)
			(layer "B.SilkS")
			(hide yes)
			(effects
				(font
					(size 1.27 1.27)
				)
				(justify mirror)
			)
		)
		(property "Value" ""
			(at 0 0 90)
			(layer "B.Fab")
			(effects
				(font
					(size 1.27 1.27)
				)
				(justify mirror)
			)
		)
		(duplicate_pad_numbers_are_jumpers no)
		(fp_line
			(start -0.7874 0.4064)
			(end 0.7874 0.4064)
			(stroke
				(width 0.1524)
				(type default)
			)
			(layer "B.SilkS")
		)
		(fp_line
			(start 0.7874 0.4064)
			(end 0.7874 -0.4064)
			(stroke
				(width 0.1524)
				(type default)
			)
			(layer "B.SilkS")
		)
		(fp_line
			(start -0.7874 -0.4064)
			(end -0.7874 0.4064)
			(stroke
				(width 0.1524)
				(type default)
			)
			(layer "B.SilkS")
		)
		(fp_line
			(start 0.7874 -0.4064)
			(end -0.7874 -0.4064)
			(stroke
				(width 0.1524)
				(type default)
			)
			(layer "B.SilkS")
		)
		(fp_line
			(start -0.67945 0.3048)
			(end -0.120396 0.3048)
			(stroke
				(width 0.1)
				(type default)
			)
			(layer "B.Fab")
		)
		(fp_line
			(start -0.120396 0.3048)
			(end -0.120396 0.2794)
			(stroke
				(width 0.1)
				(type default)
			)
			(layer "B.Fab")
		)
		(fp_line
			(start 0.12065 0.3048)
			(end 0.67945 0.3048)
			(stroke
				(width 0.1)
				(type default)
			)
			(layer "B.Fab")
		)
		(fp_line
			(start 0.67945 0.3048)
			(end 0.67945 -0.305054)
			(stroke
				(width 0.1)
				(type default)
			)
			(layer "B.Fab")
		)
		(fp_line
			(start -0.120396 0.2794)
			(end 0.12065 0.2794)
			(stroke
				(width 0.1)
				(type default)
			)
			(layer "B.Fab")
		)
		(fp_line
			(start 0.12065 0.2794)
			(end 0.12065 0.3048)
			(stroke
				(width 0.1)
				(type default)
			)
			(layer "B.Fab")
		)
		(fp_line
			(start -0.12065 -0.2794)
			(end -0.12065 -0.3048)
			(stroke
				(width 0.1)
				(type default)
			)
			(layer "B.Fab")
		)
		(fp_line
			(start 0.12065 -0.2794)
			(end -0.12065 -0.2794)
			(stroke
				(width 0.1)
				(type default)
			)
			(layer "B.Fab")
		)
		(fp_line
			(start -0.67945 -0.3048)
			(end -0.67945 0.3048)
			(stroke
				(width 0.1)
				(type default)
			)
			(layer "B.Fab")
		)
		(fp_line
			(start -0.12065 -0.3048)
			(end -0.67945 -0.3048)
			(stroke
				(width 0.1)
				(type default)
			)
			(layer "B.Fab")
		)
		(fp_line
			(start 0.12065 -0.305054)
			(end 0.12065 -0.2794)
			(stroke
				(width 0.1)
				(type default)
			)
			(layer "B.Fab")
		)
		(fp_line
			(start 0.67945 -0.305054)
			(end 0.12065 -0.305054)
			(stroke
				(width 0.1)
				(type default)
			)
			(layer "B.Fab")
		)
		(pad "1" smd circle
			(at 0.40005 0 90)
			(size 0 0)
			(layers "B.Cu" "B.Mask" "B.Paste")
			(net "PVDDIO_P0_VOS4")
		)
		(pad "2" smd circle
			(at -0.40005 0 90)
			(size 0 0)
			(layers "B.Cu" "B.Mask" "B.Paste")
			(net "PVDDIO_P0")
		)
	)
	(footprint ""
		(layer "B.Cu")
		(at 198.47433 -70.903084)
		(property "Reference" "U223"
			(at 1.73482 3.30073 0)
			(unlocked yes)
			(layer "B.SilkS")
			(effects
				(font
					(size 0.7874 0.5842)
					(thickness 0.1524)
				)
				(justify left mirror)
			)
		)
		(property "Value" ""
			(at 0 0 0)
			(layer "B.Fab")
			(effects
				(font
					(size 1.27 1.27)
				)
				(justify mirror)
			)
		)
		(duplicate_pad_numbers_are_jumpers no)
		(fp_line
			(start -2.0066 -2.5527)
			(end -2.0066 2.5527)
			(stroke
				(width 0.1524)
				(type default)
			)
			(layer "B.SilkS")
		)
		(fp_line
			(start -2.0066 2.5527)
			(end 2.0066 2.5527)
			(stroke
				(width 0.1524)
				(type default)
			)
			(layer "B.SilkS")
		)
		(fp_line
			(start -0.5715 -2.5527)
			(end -2.0066 -2.5527)
			(stroke
				(width 0.1524)
				(type default)
			)
			(layer "B.SilkS")
		)
		(fp_line
			(start 0 -1.9812)
			(end -0.5715 -2.5527)
			(stroke
				(width 0.1524)
				(type default)
			)
			(layer "B.SilkS")
		)
		(fp_line
			(start 0.5715 -2.5527)
			(end 0 -1.9812)
			(stroke
				(width 0.1524)
				(type default)
			)
			(layer "B.SilkS")
		)
		(fp_line
			(start 2.0066 -2.5527)
			(end 0.5715 -2.5527)
			(stroke
				(width 0.1524)
				(type default)
			)
			(layer "B.SilkS")
		)
		(fp_line
			(start 2.0066 2.5527)
			(end 2.0066 -2.5527)
			(stroke
				(width 0.1524)
				(type default)
			)
			(layer "B.SilkS")
		)
		(fp_poly
			(pts
				(xy 3.81 -1.905) (xy 4.36372 -2.233168) (xy 4.36372 -1.608328)
			)
			(stroke
				(width 0)
				(type default)
			)
			(fill yes)
			(layer "B.SilkS")
		)
		(fp_line
			(start -2.249932 -2.549906)
			(end -2.249932 2.549906)
			(stroke
				(width 0.1)
				(type default)
			)
			(layer "B.Fab")
		)
		(fp_line
			(start -2.249932 2.549906)
			(end 2.249932 2.549906)
			(stroke
				(width 0.1)
				(type default)
			)
			(layer "B.Fab")
		)
		(fp_line
			(start 2.249932 -2.549906)
			(end -2.249932 -2.549906)
			(stroke
				(width 0.1)
				(type default)
			)
			(layer "B.Fab")
		)
		(fp_line
			(start 2.249932 2.549906)
			(end 2.249932 -2.549906)
			(stroke
				(width 0.1)
				(type default)
			)
			(layer "B.Fab")
		)
		(fp_poly
			(pts
				(xy 4.36372 -1.608328) (xy 4.36372 -2.233168) (xy 3.81 -1.905)
			)
			(stroke
				(width 0)
				(type default)
			)
			(fill yes)
			(layer "B.Fab")
		)
		(pad "1" smd rect
			(at 2.921 -1.949958 270)
			(size 0.3556 1.4986)
			(layers "B.Cu" "B.Mask" "B.Paste")
			(net "FB_BMC_ISOLATE1")
		)
		(pad "2" smd rect
			(at 2.921 -1.299972 270)
			(size 0.3556 1.4986)
			(layers "B.Cu" "B.Mask" "B.Paste")
			(net "NCSI_BMC_TXD1_R1")
		)
		(pad "3" smd rect
			(at 2.921 -0.649986 270)
			(size 0.3556 1.4986)
			(layers "B.Cu" "B.Mask" "B.Paste")
			(net "NCSI_OCP_V3_2_TXD1")
		)
		(pad "4" smd rect
			(at 2.921 0 270)
			(size 0.3556 1.4986)
			(layers "B.Cu" "B.Mask" "B.Paste")
			(net "FB_BMC_ISOLATE1")
		)
		(pad "5" smd rect
			(at 2.921 0.649986 270)
			(size 0.3556 1.4986)
			(layers "B.Cu" "B.Mask" "B.Paste")
			(net "NCSI_BMC_TXD0_R1")
		)
		(pad "6" smd rect
			(at 2.921 1.299972 270)
			(size 0.3556 1.4986)
			(layers "B.Cu" "B.Mask" "B.Paste")
			(net "NCSI_OCP_V3_2_TXD0")
		)
		(pad "7" smd rect
			(at 2.921 1.949958 270)
			(size 0.3556 1.4986)
			(layers "B.Cu" "B.Mask" "B.Paste")
			(net "GND")
		)
		(pad "8" smd rect
			(at -2.921 1.949958 270)
			(size 0.3556 1.4986)
			(layers "B.Cu" "B.Mask" "B.Paste")
			(net "NCSI_OCP_V3_2_TX_EN")
		)
		(pad "9" smd rect
			(at -2.921 1.299972 270)
			(size 0.3556 1.4986)
			(layers "B.Cu" "B.Mask" "B.Paste")
			(net "NCSI_BMC_TX_EN_R1")
		)
		(pad "10" smd rect
			(at -2.921 0.649986 270)
			(size 0.3556 1.4986)
			(layers "B.Cu" "B.Mask" "B.Paste")
			(net "FB_BMC_ISOLATE1")
		)
		(pad "11" smd rect
			(at -2.921 0 270)
			(size 0.3556 1.4986)
			(layers "B.Cu" "B.Mask" "B.Paste")
			(net "OCP_V3_2_ISO2_RBT_ARB_OUT")
		)
		(pad "12" smd rect
			(at -2.921 -0.649986 270)
			(size 0.3556 1.4986)
			(layers "B.Cu" "B.Mask" "B.Paste")
			(net "OCP_V3_2_RBT_ARB_OUT")
		)
		(pad "13" smd rect
			(at -2.921 -1.299972 270)
			(size 0.3556 1.4986)
			(layers "B.Cu" "B.Mask" "B.Paste")
			(net "FB_BMC_ISOLATE1")
		)
		(pad "14" smd rect
			(at -2.921 -1.949958 270)
			(size 0.3556 1.4986)
			(layers "B.Cu" "B.Mask" "B.Paste")
			(net "P3V3_AUX")
		)
	)
	(footprint ""
		(layer "B.Cu")
		(at 330.947014 -398.969484)
		(property "Reference" "C633"
			(at 0 0 0)
			(layer "B.SilkS")
			(hide yes)
			(effects
				(font
					(size 1.27 1.27)
				)
				(justify mirror)
			)
		)
		(property "Value" ""
			(at 0 0 0)
			(layer "B.Fab")
			(effects
				(font
					(size 1.27 1.27)
				)
				(justify mirror)
			)
		)
		(duplicate_pad_numbers_are_jumpers no)
		(fp_line
			(start -1.524 -0.762)
			(end -1.524 0.762)
			(stroke
				(width 0.1524)
				(type default)
			)
			(layer "B.SilkS")
		)
		(fp_line
			(start -1.524 0.762)
			(end 1.524 0.762)
			(stroke
				(width 0.1524)
				(type default)
			)
			(layer "B.SilkS")
		)
		(fp_line
			(start 1.524 -0.762)
			(end -1.524 -0.762)
			(stroke
				(width 0.1524)
				(type default)
			)
			(layer "B.SilkS")
		)
		(fp_line
			(start 1.524 0.762)
			(end 1.524 -0.762)
			(stroke
				(width 0.1524)
				(type default)
			)
			(layer "B.SilkS")
		)
		(fp_line
			(start -1.1049 -0.724916)
			(end 1.1049 -0.724916)
			(stroke
				(width 0.1)
				(type default)
			)
			(layer "B.Fab")
		)
		(fp_line
			(start -1.1049 0.724916)
			(end -1.1049 -0.724916)
			(stroke
				(width 0.1)
				(type default)
			)
			(layer "B.Fab")
		)
		(fp_line
			(start 1.1049 -0.724916)
			(end 1.1049 0.724916)
			(stroke
				(width 0.1)
				(type default)
			)
			(layer "B.Fab")
		)
		(fp_line
			(start 1.1049 0.724916)
			(end -1.1049 0.724916)
			(stroke
				(width 0.1)
				(type default)
			)
			(layer "B.Fab")
		)
		(pad "1" smd rect
			(at 0.889 0)
			(size 1.016 1.27)
			(layers "B.Cu" "B.Mask" "B.Paste")
			(net "P0V9_CPU0_RT1_2A")
		)
		(pad "2" smd rect
			(at -0.889 0)
			(size 1.016 1.27)
			(layers "B.Cu" "B.Mask" "B.Paste")
			(net "GND")
		)
	)
	(footprint ""
		(layer "B.Cu")
		(at 316.93739 -76.639928 90)
		(property "Reference" "R4604"
			(at 0 0 90)
			(layer "B.SilkS")
			(hide yes)
			(effects
				(font
					(size 1.27 1.27)
				)
				(justify mirror)
			)
		)
		(property "Value" ""
			(at 0 0 90)
			(layer "B.Fab")
			(effects
				(font
					(size 1.27 1.27)
				)
				(justify mirror)
			)
		)
		(duplicate_pad_numbers_are_jumpers no)
		(fp_line
			(start 0.7874 -0.4064)
			(end -0.7874 -0.4064)
			(stroke
				(width 0.1524)
				(type default)
			)
			(layer "B.SilkS")
		)
		(fp_line
			(start -0.7874 -0.4064)
			(end -0.7874 0.4064)
			(stroke
				(width 0.1524)
				(type default)
			)
			(layer "B.SilkS")
		)
		(fp_line
			(start 0.7874 0.4064)
			(end 0.7874 -0.4064)
			(stroke
				(width 0.1524)
				(type default)
			)
			(layer "B.SilkS")
		)
		(fp_line
			(start -0.7874 0.4064)
			(end 0.7874 0.4064)
			(stroke
				(width 0.1524)
				(type default)
			)
			(layer "B.SilkS")
		)
		(fp_line
			(start 0.67945 -0.305054)
			(end 0.12065 -0.305054)
			(stroke
				(width 0.1)
				(type default)
			)
			(layer "B.Fab")
		)
		(fp_line
			(start 0.12065 -0.305054)
			(end 0.12065 -0.2794)
			(stroke
				(width 0.1)
				(type default)
			)
			(layer "B.Fab")
		)
		(fp_line
			(start -0.12065 -0.3048)
			(end -0.67945 -0.3048)
			(stroke
				(width 0.1)
				(type default)
			)
			(layer "B.Fab")
		)
		(fp_line
			(start -0.67945 -0.3048)
			(end -0.67945 0.3048)
			(stroke
				(width 0.1)
				(type default)
			)
			(layer "B.Fab")
		)
		(fp_line
			(start 0.12065 -0.2794)
			(end -0.12065 -0.2794)
			(stroke
				(width 0.1)
				(type default)
			)
			(layer "B.Fab")
		)
		(fp_line
			(start -0.12065 -0.2794)
			(end -0.12065 -0.3048)
			(stroke
				(width 0.1)
				(type default)
			)
			(layer "B.Fab")
		)
		(fp_line
			(start 0.12065 0.2794)
			(end 0.12065 0.3048)
			(stroke
				(width 0.1)
				(type default)
			)
			(layer "B.Fab")
		)
		(fp_line
			(start -0.120396 0.2794)
			(end 0.12065 0.2794)
			(stroke
				(width 0.1)
				(type default)
			)
			(layer "B.Fab")
		)
		(fp_line
			(start 0.67945 0.3048)
			(end 0.67945 -0.305054)
			(stroke
				(width 0.1)
				(type default)
			)
			(layer "B.Fab")
		)
		(fp_line
			(start 0.12065 0.3048)
			(end 0.67945 0.3048)
			(stroke
				(width 0.1)
				(type default)
			)
			(layer "B.Fab")
		)
		(fp_line
			(start -0.120396 0.3048)
			(end -0.120396 0.2794)
			(stroke
				(width 0.1)
				(type default)
			)
			(layer "B.Fab")
		)
		(fp_line
			(start -0.67945 0.3048)
			(end -0.120396 0.3048)
			(stroke
				(width 0.1)
				(type default)
			)
			(layer "B.Fab")
		)
		(pad "1" smd circle
			(at 0.40005 0 270)
			(size 0 0)
			(layers "B.Cu" "B.Mask" "B.Paste")
			(net "P3V3_AUX")
		)
		(pad "2" smd circle
			(at -0.40005 0 270)
			(size 0 0)
			(layers "B.Cu" "B.Mask" "B.Paste")
			(net "PWRGD_PS_PWROK_PLD_N")
		)
	)
)
